# S9S_MB_2U (Grand Teton) — schematic netlist excerpt (pin names and nets, part order shuffled) for the footprints in the layout excerpt that follows; sources: Cadence DE-HDL packaged netlist, KiCad conversion of 03242023_DA0F0TMBIJ0_F0T_Motherboard_J_brd_V01_OCP.brd

PR1726  Q_RES  8.87K 1% EMPTY  pkg 0402LF  page 293 : A = PVCCINFAON_CPU1_LSET1 ; B = GND
C1871  Q_CAP  0.1UF 25V 10% X7R  pkg 0402  page 167 : A = P2E_MB_BMC_TX_BUF_DN<0> ; B = P2E_MB_BMC_TX_BUF_C_DN<0>
C715  Q_CAP_DIFFBUS  DIFF BUS_0.22UF 6.3V 20% X6S  pkg C0201  page 176 : \1\ = P5E_CPU1_PE0_TX_C_DP<13> ; \2\ = P5E_CPU1_PE0_TX_DP<13>

(kicad_pcb
	(version 20260206)
	(generator "pcbnew")
	(generator_version "10.0")
	(general
		(thickness 1.6)
		(legacy_teardrops no)
	)
	(paper "A4")
	(title_block
		(title "03242023_DA0F0TMBIJ0_F0T_Motherboard_J_brd_V01_OCP.brd")
		(comment 1 "Grand Teton / footprints 2584-2586 of 6105")
	)
	(layers
		(0 "F.Cu" signal "TOP")
		(4 "In1.Cu" signal "GND")
		(6 "In2.Cu" signal "IN1")
		(8 "In3.Cu" signal "GND1")
		(10 "In4.Cu" signal "IN2")
		(12 "In5.Cu" signal "GND2")
		(14 "In6.Cu" signal "IN3")
		(16 "In7.Cu" signal "GND3")
		(18 "In8.Cu" signal "VCC")
		(20 "In9.Cu" signal "VCC1")
		(22 "In10.Cu" signal "GND4")
		(24 "In11.Cu" signal "IN4")
		(26 "In12.Cu" signal "GND5")
		(28 "In13.Cu" signal "IN5")
		(30 "In14.Cu" signal "GND6")
		(32 "In15.Cu" signal "IN6")
		(34 "In16.Cu" signal "GND7")
		(2 "B.Cu" signal "BOTTOM")
		(9 "F.Adhes" user "F.Adhesive")
		(11 "B.Adhes" user "B.Adhesive")
		(13 "F.Paste" user "Package Geometry/Pastemask Top")
		(15 "B.Paste" user "Package Geometry/Pastemask Bottom")
		(5 "F.SilkS" user "Ref Des/Silkscreen Top")
		(7 "B.SilkS" user "Ref Des/Silkscreen Bottom")
		(1 "F.Mask" user "Board Geometry/Soldermask Top")
		(3 "B.Mask" user "Board Geometry/Soldermask Bottom")
		(17 "Dwgs.User" user "User.Drawings")
		(19 "Cmts.User" user "User.Comments")
		(21 "Eco1.User" user "User.Eco1")
		(23 "Eco2.User" user "User.Eco2")
		(25 "Edge.Cuts" user "Board Geometry/Outline")
		(27 "Margin" user)
		(31 "F.CrtYd" user "Package Geometry/Place Bound Top")
		(29 "B.CrtYd" user "Package Geometry/Place Bound Bottom")
		(35 "F.Fab" user "Ref Des/Assembly Top")
		(33 "B.Fab" user "Ref Des/Assembly Bottom")
	)
	(footprint ""
		(layer "F.Cu")
		(at 19.927824 -396.011908 90)
		(property "Reference" "C1871"
			(at 0 0 90)
			(layer "F.SilkS")
			(hide yes)
			(effects
				(font
					(size 1.27 1.27)
				)
			)
		)
		(property "Value" ""
			(at 0 0 90)
			(layer "F.Fab")
			(effects
				(font
					(size 1.27 1.27)
				)
			)
		)
		(duplicate_pad_numbers_are_jumpers no)
		(fp_line
			(start 0.7874 -0.4064)
			(end 0.7874 0.4064)
			(stroke
				(width 0.1524)
				(type default)
			)
			(layer "F.SilkS")
		)
		(fp_line
			(start -0.7874 -0.4064)
			(end -0.018288 -0.4064)
			(stroke
				(width 0.1524)
				(type default)
			)
			(layer "F.SilkS")
		)
		(fp_line
			(start 0.7874 0.4064)
			(end -0.7874 0.4064)
			(stroke
				(width 0.1524)
				(type default)
			)
			(layer "F.SilkS")
		)
		(fp_line
			(start 0.6858 -0.3048)
			(end 0.6858 0.3048)
			(stroke
				(width 0.1)
				(type default)
			)
			(layer "F.Fab")
		)
		(fp_line
			(start 0.1016 -0.3048)
			(end 0.6858 -0.3048)
			(stroke
				(width 0.1)
				(type default)
			)
			(layer "F.Fab")
		)
		(fp_line
			(start -0.1016 -0.3048)
			(end -0.1016 -0.2794)
			(stroke
				(width 0.1)
				(type default)
			)
			(layer "F.Fab")
		)
		(fp_line
			(start -0.6858 -0.3048)
			(end -0.1016 -0.3048)
			(stroke
				(width 0.1)
				(type default)
			)
			(layer "F.Fab")
		)
		(fp_line
			(start 0.1016 -0.2794)
			(end 0.1016 -0.3048)
			(stroke
				(width 0.1)
				(type default)
			)
			(layer "F.Fab")
		)
		(fp_line
			(start -0.1016 -0.2794)
			(end 0.1016 -0.2794)
			(stroke
				(width 0.1)
				(type default)
			)
			(layer "F.Fab")
		)
		(fp_line
			(start 0.1016 0.2794)
			(end -0.1016 0.2794)
			(stroke
				(width 0.1)
				(type default)
			)
			(layer "F.Fab")
		)
		(fp_line
			(start -0.1016 0.2794)
			(end -0.1016 0.3048)
			(stroke
				(width 0.1)
				(type default)
			)
			(layer "F.Fab")
		)
		(fp_line
			(start 0.6858 0.3048)
			(end 0.1016 0.3048)
			(stroke
				(width 0.1)
				(type default)
			)
			(layer "F.Fab")
		)
		(fp_line
			(start 0.1016 0.3048)
			(end 0.1016 0.2794)
			(stroke
				(width 0.1)
				(type default)
			)
			(layer "F.Fab")
		)
		(fp_line
			(start -0.1016 0.3048)
			(end -0.6858 0.3048)
			(stroke
				(width 0.1)
				(type default)
			)
			(layer "F.Fab")
		)
		(fp_line
			(start -0.6858 0.3048)
			(end -0.6858 -0.3048)
			(stroke
				(width 0.1)
				(type default)
			)
			(layer "F.Fab")
		)
		(pad "1" smd rect
			(at -0.40005 0 270)
			(size 0.4572 0.508)
			(layers "F.Cu" "F.Mask" "F.Paste")
			(net "P2E_MB_BMC_TX_BUF_DN<0>")
		)
		(pad "2" smd rect
			(at 0.40005 0 270)
			(size 0.4572 0.508)
			(layers "F.Cu" "F.Mask" "F.Paste")
			(net "P2E_MB_BMC_TX_BUF_C_DN<0>")
		)
	)
	(footprint ""
		(layer "F.Cu")
		(at 54.995318 -402.371052 -90)
		(property "Reference" "C715"
			(at 0 0 270)
			(layer "F.SilkS")
			(hide yes)
			(effects
				(font
					(size 1.27 1.27)
				)
			)
		)
		(property "Value" ""
			(at 0 0 270)
			(layer "F.Fab")
			(effects
				(font
					(size 1.27 1.27)
				)
			)
		)
		(duplicate_pad_numbers_are_jumpers no)
		(fp_line
			(start -0.299974 0.150114)
			(end -0.299974 -0.150114)
			(stroke
				(width 0.1)
				(type default)
			)
			(layer "F.Fab")
		)
		(fp_line
			(start 0.299974 0.150114)
			(end -0.299974 0.150114)
			(stroke
				(width 0.1)
				(type default)
			)
			(layer "F.Fab")
		)
		(fp_line
			(start -0.299974 -0.150114)
			(end 0.299974 -0.150114)
			(stroke
				(width 0.1)
				(type default)
			)
			(layer "F.Fab")
		)
		(fp_line
			(start 0.299974 -0.150114)
			(end 0.299974 0.150114)
			(stroke
				(width 0.1)
				(type default)
			)
			(layer "F.Fab")
		)
		(pad "1" smd rect
			(at -0.2667 0 270)
			(size 0.3048 0.381)
			(layers "F.Cu" "F.Mask" "F.Paste")
			(net "P5E_CPU1_PE0_TX_C_DP<13>")
		)
		(pad "2" smd rect
			(at 0.2667 0 270)
			(size 0.3048 0.381)
			(layers "F.Cu" "F.Mask" "F.Paste")
			(net "P5E_CPU1_PE0_TX_DP<13>")
		)
	)
	(footprint ""
		(layer "F.Cu")
		(at 49.755552 -155.186634 90)
		(property "Reference" "PR1726"
			(at 0 0 90)
			(layer "F.SilkS")
			(hide yes)
			(effects
				(font
					(size 1.27 1.27)
				)
			)
		)
		(property "Value" ""
			(at 0 0 90)
			(layer "F.Fab")
			(effects
				(font
					(size 1.27 1.27)
				)
			)
		)
		(duplicate_pad_numbers_are_jumpers no)
		(fp_line
			(start 0.7874 -0.4064)
			(end 0.7874 0.4064)
			(stroke
				(width 0.1524)
				(type default)
			)
			(layer "F.SilkS")
		)
		(fp_line
			(start -0.7874 -0.4064)
			(end 0.7874 -0.4064)
			(stroke
				(width 0.1524)
				(type default)
			)
			(layer "F.SilkS")
		)
		(fp_line
			(start 0.7874 0.4064)
			(end -0.7874 0.4064)
			(stroke
				(width 0.1524)
				(type default)
			)
			(layer "F.SilkS")
		)
		(fp_line
			(start -0.7874 0.4064)
			(end -0.7874 -0.4064)
			(stroke
				(width 0.1524)
				(type default)
			)
			(layer "F.SilkS")
		)
		(fp_line
			(start -0.12065 -0.305054)
			(end -0.12065 -0.2794)
			(stroke
				(width 0.1)
				(type default)
			)
			(layer "F.Fab")
		)
		(fp_line
			(start -0.67945 -0.305054)
			(end -0.12065 -0.305054)
			(stroke
				(width 0.1)
				(type default)
			)
			(layer "F.Fab")
		)
		(fp_line
			(start 0.67945 -0.3048)
			(end 0.67945 0.3048)
			(stroke
				(width 0.1)
				(type default)
			)
			(layer "F.Fab")
		)
		(fp_line
			(start 0.12065 -0.3048)
			(end 0.67945 -0.3048)
			(stroke
				(width 0.1)
				(type default)
			)
			(layer "F.Fab")
		)
		(fp_line
			(start 0.12065 -0.2794)
			(end 0.12065 -0.3048)
			(stroke
				(width 0.1)
				(type default)
			)
			(layer "F.Fab")
		)
		(fp_line
			(start -0.12065 -0.2794)
			(end 0.12065 -0.2794)
			(stroke
				(width 0.1)
				(type default)
			)
			(layer "F.Fab")
		)
		(fp_line
			(start 0.120396 0.2794)
			(end -0.12065 0.2794)
			(stroke
				(width 0.1)
				(type default)
			)
			(layer "F.Fab")
		)
		(fp_line
			(start -0.12065 0.2794)
			(end -0.12065 0.3048)
			(stroke
				(width 0.1)
				(type default)
			)
			(layer "F.Fab")
		)
		(fp_line
			(start 0.67945 0.3048)
			(end 0.120396 0.3048)
			(stroke
				(width 0.1)
				(type default)
			)
			(layer "F.Fab")
		)
		(fp_line
			(start 0.120396 0.3048)
			(end 0.120396 0.2794)
			(stroke
				(width 0.1)
				(type default)
			)
			(layer "F.Fab")
		)
		(fp_line
			(start -0.12065 0.3048)
			(end -0.67945 0.3048)
			(stroke
				(width 0.1)
				(type default)
			)
			(layer "F.Fab")
		)
		(fp_line
			(start -0.67945 0.3048)
			(end -0.67945 -0.305054)
			(stroke
				(width 0.1)
				(type default)
			)
			(layer "F.Fab")
		)
		(pad "1" smd circle
			(at -0.40005 0 90)
			(size 0 0)
			(layers "F.Cu" "F.Mask" "F.Paste")
			(net "PVCCINFAON_CPU1_LSET1")
		)
		(pad "2" smd circle
			(at 0.40005 0 90)
			(size 0 0)
			(layers "F.Cu" "F.Mask" "F.Paste")
			(net "GND")
		)
	)
)
